(kicad_pcb
	(version 20260206)
	(generator "pcbnew")
	(generator_version "10.0")
	(general
		(thickness 1.6)
		(legacy_teardrops no)
	)
	(paper "A4")
	(title_block
		(title "03242023_DA0F0TMBIJ0_F0T_Motherboard_J_brd_V01_OCP.brd")
		(comment 1 "Grand Teton / footprints 4936-4941 of 6105")
	)
	(layers
		(0 "F.Cu" signal "TOP")
		(4 "In1.Cu" signal "GND")
		(6 "In2.Cu" signal "IN1")
		(8 "In3.Cu" signal "GND1")
		(10 "In4.Cu" signal "IN2")
		(12 "In5.Cu" signal "GND2")
		(14 "In6.Cu" signal "IN3")
		(16 "In7.Cu" signal "GND3")
		(18 "In8.Cu" signal "VCC")
		(20 "In9.Cu" signal "VCC1")
		(22 "In10.Cu" signal "GND4")
		(24 "In11.Cu" signal "IN4")
		(26 "In12.Cu" signal "GND5")
		(28 "In13.Cu" signal "IN5")
		(30 "In14.Cu" signal "GND6")
		(32 "In15.Cu" signal "IN6")
		(34 "In16.Cu" signal "GND7")
		(2 "B.Cu" signal "BOTTOM")
		(9 "F.Adhes" user "F.Adhesive")
		(11 "B.Adhes" user "B.Adhesive")
		(13 "F.Paste" user "Package Geometry/Pastemask Top")
		(15 "B.Paste" user "Package Geometry/Pastemask Bottom")
		(5 "F.SilkS" user "Ref Des/Silkscreen Top")
		(7 "B.SilkS" user "Ref Des/Silkscreen Bottom")
		(1 "F.Mask" user "Board Geometry/Soldermask Top")
		(3 "B.Mask" user "Board Geometry/Soldermask Bottom")
		(17 "Dwgs.User" user "User.Drawings")
		(19 "Cmts.User" user "User.Comments")
		(21 "Eco1.User" user "User.Eco1")
		(23 "Eco2.User" user "User.Eco2")
		(25 "Edge.Cuts" user "Board Geometry/Outline")
		(27 "Margin" user)
		(31 "F.CrtYd" user "Package Geometry/Place Bound Top")
		(29 "B.CrtYd" user "Package Geometry/Place Bound Bottom")
		(35 "F.Fab" user "Ref Des/Assembly Top")
		(33 "B.Fab" user "Ref Des/Assembly Bottom")
	)
	(footprint ""
		(layer "B.Cu")
		(at 180.555646 -110.975394 -90)
		(property "Reference" "C1118"
			(at 0 0 90)
			(layer "B.SilkS")
			(hide yes)
			(effects
				(font
					(size 1.27 1.27)
				)
				(justify mirror)
			)
		)
		(property "Value" ""
			(at 0 0 90)
			(layer "B.Fab")
			(effects
				(font
					(size 1.27 1.27)
				)
				(justify mirror)
			)
		)
		(duplicate_pad_numbers_are_jumpers no)
		(fp_line
			(start -0.69215 0.2921)
			(end 0.69215 0.2921)
			(stroke
				(width 0.1524)
				(type default)
			)
			(layer "B.SilkS")
		)
		(fp_line
			(start 0.69215 0.2921)
			(end 0.69215 -0.2921)
			(stroke
				(width 0.1524)
				(type default)
			)
			(layer "B.SilkS")
		)
		(fp_line
			(start -0.69215 -0.2921)
			(end -0.69215 0.2921)
			(stroke
				(width 0.1524)
				(type default)
			)
			(layer "B.SilkS")
		)
		(fp_line
			(start 0.69215 -0.2921)
			(end -0.69215 -0.2921)
			(stroke
				(width 0.1524)
				(type default)
			)
			(layer "B.SilkS")
		)
		(fp_line
			(start -0.51435 0.2794)
			(end 0.51435 0.2794)
			(stroke
				(width 0.1)
				(type default)
			)
			(layer "B.Fab")
		)
		(fp_line
			(start 0.51435 0.2794)
			(end 0.51435 -0.2794)
			(stroke
				(width 0.1)
				(type default)
			)
			(layer "B.Fab")
		)
		(fp_line
			(start -0.51435 -0.2794)
			(end -0.51435 0.2794)
			(stroke
				(width 0.1)
				(type default)
			)
			(layer "B.Fab")
		)
		(fp_line
			(start 0.51435 -0.2794)
			(end -0.51435 -0.2794)
			(stroke
				(width 0.1)
				(type default)
			)
			(layer "B.Fab")
		)
		(pad "1" smd circle
			(at 0.40005 0 90)
			(size 0 0)
			(layers "B.Cu" "B.Mask" "B.Paste")
			(net "P3V3_AUX_FPGA_VCCIO3")
		)
		(pad "2" smd circle
			(at -0.40005 0 90)
			(size 0 0)
			(layers "B.Cu" "B.Mask" "B.Paste")
			(net "GND")
		)
		(zone
			(layer "B.Cu")
			(hatch none 0.5)
			(connect_pads
				(clearance 0)
			)
			(min_thickness 0.25)
			(keepout
				(tracks not_allowed)
				(vias allowed)
				(pads allowed)
				(copperpour not_allowed)
				(footprints allowed)
			)
			(placement
				(enabled no)
				(sheetname "")
			)
			(fill
				(thermal_gap 0.5)
				(thermal_bridge_width 0.5)
				(island_removal_mode 0)
			)
			(polygon
				(pts
					(xy 180.468016 -110.784894) (xy 180.40985 -110.876334) (xy 180.40985 -111.075724) (xy 180.468016 -111.165894)
					(xy 180.643276 -111.165894) (xy 180.701696 -111.075724) (xy 180.701696 -110.876334) (xy 180.64353 -110.784894)
				)
			)
		)
	)
	(footprint ""
		(layer "B.Cu")
		(at 101.404928 -210.418934 180)
		(property "Reference" "C472"
			(at 0 0 0)
			(layer "B.SilkS")
			(hide yes)
			(effects
				(font
					(size 1.27 1.27)
				)
				(justify mirror)
			)
		)
		(property "Value" ""
			(at 0 0 0)
			(layer "B.Fab")
			(effects
				(font
					(size 1.27 1.27)
				)
				(justify mirror)
			)
		)
		(duplicate_pad_numbers_are_jumpers no)
		(fp_line
			(start 1.2954 0.5842)
			(end 1.2954 -0.5842)
			(stroke
				(width 0.1524)
				(type default)
			)
			(layer "B.SilkS")
		)
		(fp_line
			(start 1.2954 -0.5842)
			(end -1.2954 -0.5842)
			(stroke
				(width 0.1524)
				(type default)
			)
			(layer "B.SilkS")
		)
		(fp_line
			(start 0 -0.5842)
			(end 0 0.5842)
			(stroke
				(width 0.1524)
				(type default)
			)
			(layer "B.SilkS")
		)
		(fp_line
			(start -1.2954 0.5842)
			(end 1.2954 0.5842)
			(stroke
				(width 0.1524)
				(type default)
			)
			(layer "B.SilkS")
		)
		(fp_line
			(start -1.2954 -0.5842)
			(end -1.2954 0.5842)
			(stroke
				(width 0.1524)
				(type default)
			)
			(layer "B.SilkS")
		)
		(fp_line
			(start 1.1938 0.4064)
			(end 1.1938 -0.4064)
			(stroke
				(width 0.1)
				(type default)
			)
			(layer "B.Fab")
		)
		(fp_line
			(start 1.1938 -0.4064)
			(end 0.8636 -0.4064)
			(stroke
				(width 0.1)
				(type default)
			)
			(layer "B.Fab")
		)
		(fp_line
			(start 0.8636 0.4572)
			(end 0.8636 0.4064)
			(stroke
				(width 0.1)
				(type default)
			)
			(layer "B.Fab")
		)
		(fp_line
			(start 0.8636 0.4064)
			(end 1.1938 0.4064)
			(stroke
				(width 0.1)
				(type default)
			)
			(layer "B.Fab")
		)
		(fp_line
			(start 0.8636 -0.4064)
			(end 0.8636 -0.4572)
			(stroke
				(width 0.1)
				(type default)
			)
			(layer "B.Fab")
		)
		(fp_line
			(start 0.8636 -0.4572)
			(end -0.8636 -0.4572)
			(stroke
				(width 0.1)
				(type default)
			)
			(layer "B.Fab")
		)
		(fp_line
			(start -0.8636 0.4572)
			(end 0.8636 0.4572)
			(stroke
				(width 0.1)
				(type default)
			)
			(layer "B.Fab")
		)
		(fp_line
			(start -0.8636 0.4064)
			(end -0.8636 0.4572)
			(stroke
				(width 0.1)
				(type default)
			)
			(layer "B.Fab")
		)
		(fp_line
			(start -0.8636 -0.4064)
			(end -1.1938 -0.4064)
			(stroke
				(width 0.1)
				(type default)
			)
			(layer "B.Fab")
		)
		(fp_line
			(start -0.8636 -0.4572)
			(end -0.8636 -0.4064)
			(stroke
				(width 0.1)
				(type default)
			)
			(layer "B.Fab")
		)
		(fp_line
			(start -1.1938 0.4064)
			(end -0.8636 0.4064)
			(stroke
				(width 0.1)
				(type default)
			)
			(layer "B.Fab")
		)
		(fp_line
			(start -1.1938 -0.4064)
			(end -1.1938 0.4064)
			(stroke
				(width 0.1)
				(type default)
			)
			(layer "B.Fab")
		)
		(pad "1" smd rect
			(at 0.7366 0 90)
			(size 0.7112 0.8128)
			(layers "B.Cu" "B.Mask" "B.Paste")
			(net "PVCCFA_EHV_CPU1")
		)
		(pad "2" smd rect
			(at -0.7366 0 90)
			(size 0.7112 0.8128)
			(layers "B.Cu" "B.Mask" "B.Paste")
			(net "GND")
		)
	)
	(footprint ""
		(layer "B.Cu")
		(at 292.983158 -151.775668 -90)
		(property "Reference" "R682"
			(at 0 0 90)
			(layer "B.SilkS")
			(hide yes)
			(effects
				(font
					(size 1.27 1.27)
				)
				(justify mirror)
			)
		)
		(property "Value" ""
			(at 0 0 90)
			(layer "B.Fab")
			(effects
				(font
					(size 1.27 1.27)
				)
				(justify mirror)
			)
		)
		(duplicate_pad_numbers_are_jumpers no)
		(fp_line
			(start -0.7874 0.4064)
			(end 0.7874 0.4064)
			(stroke
				(width 0.1524)
				(type default)
			)
			(layer "B.SilkS")
		)
		(fp_line
			(start 0.7874 0.4064)
			(end 0.7874 -0.4064)
			(stroke
				(width 0.1524)
				(type default)
			)
			(layer "B.SilkS")
		)
		(fp_line
			(start -0.7874 -0.4064)
			(end -0.7874 0.4064)
			(stroke
				(width 0.1524)
				(type default)
			)
			(layer "B.SilkS")
		)
		(fp_line
			(start 0.7874 -0.4064)
			(end -0.7874 -0.4064)
			(stroke
				(width 0.1524)
				(type default)
			)
			(layer "B.SilkS")
		)
		(fp_line
			(start -0.67945 0.3048)
			(end -0.120396 0.3048)
			(stroke
				(width 0.1)
				(type default)
			)
			(layer "B.Fab")
		)
		(fp_line
			(start -0.120396 0.3048)
			(end -0.120396 0.2794)
			(stroke
				(width 0.1)
				(type default)
			)
			(layer "B.Fab")
		)
		(fp_line
			(start 0.12065 0.3048)
			(end 0.67945 0.3048)
			(stroke
				(width 0.1)
				(type default)
			)
			(layer "B.Fab")
		)
		(fp_line
			(start 0.67945 0.3048)
			(end 0.67945 -0.305054)
			(stroke
				(width 0.1)
				(type default)
			)
			(layer "B.Fab")
		)
		(fp_line
			(start -0.120396 0.2794)
			(end 0.12065 0.2794)
			(stroke
				(width 0.1)
				(type default)
			)
			(layer "B.Fab")
		)
		(fp_line
			(start 0.12065 0.2794)
			(end 0.12065 0.3048)
			(stroke
				(width 0.1)
				(type default)
			)
			(layer "B.Fab")
		)
		(fp_line
			(start -0.12065 -0.2794)
			(end -0.12065 -0.3048)
			(stroke
				(width 0.1)
				(type default)
			)
			(layer "B.Fab")
		)
		(fp_line
			(start 0.12065 -0.2794)
			(end -0.12065 -0.2794)
			(stroke
				(width 0.1)
				(type default)
			)
			(layer "B.Fab")
		)
		(fp_line
			(start -0.67945 -0.3048)
			(end -0.67945 0.3048)
			(stroke
				(width 0.1)
				(type default)
			)
			(layer "B.Fab")
		)
		(fp_line
			(start -0.12065 -0.3048)
			(end -0.67945 -0.3048)
			(stroke
				(width 0.1)
				(type default)
			)
			(layer "B.Fab")
		)
		(fp_line
			(start 0.12065 -0.305054)
			(end 0.12065 -0.2794)
			(stroke
				(width 0.1)
				(type default)
			)
			(layer "B.Fab")
		)
		(fp_line
			(start 0.67945 -0.305054)
			(end 0.12065 -0.305054)
			(stroke
				(width 0.1)
				(type default)
			)
			(layer "B.Fab")
		)
		(pad "1" smd circle
			(at 0.40005 0 90)
			(size 0 0)
			(layers "B.Cu" "B.Mask" "B.Paste")
			(net "I3C_SPD_DDRABCD_CPU0_R_SCL")
		)
		(pad "2" smd circle
			(at -0.40005 0 90)
			(size 0 0)
			(layers "B.Cu" "B.Mask" "B.Paste")
			(net "I3C_SPD_DDRABCD_CPU0_LVC1_R_SCL")
		)
	)
	(footprint ""
		(layer "B.Cu")
		(at 501.233948 -303.58334 -90)
		(property "Reference" "X26"
			(at 3.427476 3.336798 270)
			(unlocked yes)
			(layer "B.SilkS")
			(effects
				(font
					(size 0.7874 0.5842)
					(thickness 0.1524)
				)
				(justify left mirror)
			)
		)
		(property "Value" ""
			(at 0 0 90)
			(layer "B.Fab")
			(effects
				(font
					(size 1.27 1.27)
				)
				(justify mirror)
			)
		)
		(property "Device Type" "TP_TDR_4P_FTS_TH-TP_TDR_4P_DIPA"
			(at -1.30175 1.27 180)
			(unlocked yes)
			(layer "B.Fab")
			(hide yes)
			(effects
				(font
					(size 0.635 0.4064)
					(thickness 0.1524)
				)
				(justify mirror)
			)
		)
		(property "User Part Number" "N_A"
			(at -1.30175 1.27 180)
			(unlocked yes)
			(layer "Cmts.User")
			(hide yes)
			(effects
				(font
					(size 0.635 0.4064)
					(thickness 0.1524)
				)
				(justify mirror)
			)
		)
		(duplicate_pad_numbers_are_jumpers no)
		(fp_line
			(start -2.54 3.81)
			(end -2.54 3.6703)
			(stroke
				(width 0.1524)
				(type default)
			)
			(layer "B.SilkS")
		)
		(fp_line
			(start 0 3.81)
			(end -2.54 3.81)
			(stroke
				(width 0.1524)
				(type default)
			)
			(layer "B.SilkS")
		)
		(fp_line
			(start 0 3.175)
			(end 0 3.81)
			(stroke
				(width 0.1524)
				(type default)
			)
			(layer "B.SilkS")
		)
		(fp_line
			(start -2.54 1.4097)
			(end -2.54 1.1303)
			(stroke
				(width 0.1524)
				(type default)
			)
			(layer "B.SilkS")
		)
		(fp_line
			(start 0 0.635)
			(end 0 1.905)
			(stroke
				(width 0.1524)
				(type default)
			)
			(layer "B.SilkS")
		)
		(fp_line
			(start -2.54 -1.1303)
			(end -2.54 -1.27)
			(stroke
				(width 0.1524)
				(type default)
			)
			(layer "B.SilkS")
		)
		(fp_line
			(start -2.54 -1.27)
			(end 0 -1.27)
			(stroke
				(width 0.1524)
				(type default)
			)
			(layer "B.SilkS")
		)
		(fp_line
			(start 0 -1.27)
			(end 0 -0.635)
			(stroke
				(width 0.1524)
				(type default)
			)
			(layer "B.SilkS")
		)
		(fp_poly
			(pts
				(xy 3.043428 -0.804164) (xy 3.043428 0.719836) (xy 1.519428 -0.042164)
			)
			(stroke
				(width 0)
				(type default)
			)
			(fill yes)
			(layer "B.SilkS")
		)
		(fp_line
			(start -2.54 3.81)
			(end -2.54 -1.27)
			(stroke
				(width 0.1)
				(type default)
			)
			(layer "B.Fab")
		)
		(fp_line
			(start 0 3.81)
			(end -2.54 3.81)
			(stroke
				(width 0.1)
				(type default)
			)
			(layer "B.Fab")
		)
		(fp_line
			(start -2.54 -1.27)
			(end 0 -1.27)
			(stroke
				(width 0.1)
				(type default)
			)
			(layer "B.Fab")
		)
		(fp_line
			(start 0 -1.27)
			(end 0 3.81)
			(stroke
				(width 0.1)
				(type default)
			)
			(layer "B.Fab")
		)
		(fp_poly
			(pts
				(xy 0.761746 0) (xy 2.285746 -0.762) (xy 2.285746 0.762)
			)
			(stroke
				(width 0)
				(type default)
			)
			(fill yes)
			(layer "B.Fab")
		)
		(pad "1" thru_hole circle
			(at 0 0 90)
			(size 1.0033 1.0033)
			(drill 0.249936)
			(layers "*.Cu" "*.Mask")
			(remove_unused_layers no)
			(net "TDR_DIFF_85_IN6_DP")
			(clearance 0.10795)
			(padstack
				(mode front_inner_back)
				(layer "Inner"
					(shape circle)
					(size 0.8001 0.8001)
					(clearance 0.1524)
				)
				(layer "B.Cu"
					(shape circle)
					(size 1.0033 1.0033)
					(thermal_gap 0.10795)
					(clearance 0.10795)
				)
			)
		)
		(pad "2" thru_hole circle
			(at -2.54 0 90)
			(size 1.9939 1.9939)
			(drill 0.249936)
			(layers "*.Cu" "*.Mask")
			(remove_unused_layers no)
			(net "T1_GND")
			(clearance 0.10795)
			(padstack
				(mode front_inner_back)
				(layer "Inner"
					(shape circle)
					(size 0.8001 0.8001)
					(clearance 0.1524)
				)
				(layer "B.Cu"
					(shape circle)
					(size 1.9939 1.9939)
					(thermal_gap 0.10795)
					(clearance 0.10795)
				)
			)
		)
		(pad "3" thru_hole circle
			(at -2.54 2.54 90)
			(size 1.9939 1.9939)
			(drill 0.249936)
			(layers "*.Cu" "*.Mask")
			(remove_unused_layers no)
			(net "T1_GND")
			(clearance 0.10795)
			(padstack
				(mode front_inner_back)
				(layer "Inner"
					(shape circle)
					(size 0.8001 0.8001)
					(clearance 0.1524)
				)
				(layer "B.Cu"
					(shape circle)
					(size 1.9939 1.9939)
					(thermal_gap 0.10795)
					(clearance 0.10795)
				)
			)
		)
		(pad "4" thru_hole circle
			(at 0 2.54 90)
			(size 1.0033 1.0033)
			(drill 0.249936)
			(layers "*.Cu" "*.Mask")
			(remove_unused_layers no)
			(net "TDR_DIFF_85_IN6_DN")
			(clearance 0.10795)
			(padstack
				(mode front_inner_back)
				(layer "Inner"
					(shape circle)
					(size 0.8001 0.8001)
					(clearance 0.1524)
				)
				(layer "B.Cu"
					(shape circle)
					(size 1.0033 1.0033)
					(thermal_gap 0.10795)
					(clearance 0.10795)
				)
			)
		)
	)
	(footprint ""
		(layer "B.Cu")
		(at 252.349 -100.613718 180)
		(property "Reference" "C1313"
			(at 0 0 0)
			(layer "B.SilkS")
			(hide yes)
			(effects
				(font
					(size 1.27 1.27)
				)
				(justify mirror)
			)
		)
		(property "Value" ""
			(at 0 0 0)
			(layer "B.Fab")
			(effects
				(font
					(size 1.27 1.27)
				)
				(justify mirror)
			)
		)
		(duplicate_pad_numbers_are_jumpers no)
		(fp_line
			(start 1.2954 0.5842)
			(end 1.2954 -0.5842)
			(stroke
				(width 0.1524)
				(type default)
			)
			(layer "B.SilkS")
		)
		(fp_line
			(start 1.2954 -0.5842)
			(end -1.2954 -0.5842)
			(stroke
				(width 0.1524)
				(type default)
			)
			(layer "B.SilkS")
		)
		(fp_line
			(start 0 -0.5842)
			(end 0 0.5842)
			(stroke
				(width 0.1524)
				(type default)
			)
			(layer "B.SilkS")
		)
		(fp_line
			(start -1.2954 0.5842)
			(end 1.2954 0.5842)
			(stroke
				(width 0.1524)
				(type default)
			)
			(layer "B.SilkS")
		)
		(fp_line
			(start -1.2954 -0.5842)
			(end -1.2954 0.5842)
			(stroke
				(width 0.1524)
				(type default)
			)
			(layer "B.SilkS")
		)
		(fp_line
			(start 1.1938 0.4064)
			(end 1.1938 -0.4064)
			(stroke
				(width 0.1)
				(type default)
			)
			(layer "B.Fab")
		)
		(fp_line
			(start 1.1938 -0.4064)
			(end 0.8636 -0.4064)
			(stroke
				(width 0.1)
				(type default)
			)
			(layer "B.Fab")
		)
		(fp_line
			(start 0.8636 0.4572)
			(end 0.8636 0.4064)
			(stroke
				(width 0.1)
				(type default)
			)
			(layer "B.Fab")
		)
		(fp_line
			(start 0.8636 0.4064)
			(end 1.1938 0.4064)
			(stroke
				(width 0.1)
				(type default)
			)
			(layer "B.Fab")
		)
		(fp_line
			(start 0.8636 -0.4064)
			(end 0.8636 -0.4572)
			(stroke
				(width 0.1)
				(type default)
			)
			(layer "B.Fab")
		)
		(fp_line
			(start 0.8636 -0.4572)
			(end -0.8636 -0.4572)
			(stroke
				(width 0.1)
				(type default)
			)
			(layer "B.Fab")
		)
		(fp_line
			(start -0.8636 0.4572)
			(end 0.8636 0.4572)
			(stroke
				(width 0.1)
				(type default)
			)
			(layer "B.Fab")
		)
		(fp_line
			(start -0.8636 0.4064)
			(end -0.8636 0.4572)
			(stroke
				(width 0.1)
				(type default)
			)
			(layer "B.Fab")
		)
		(fp_line
			(start -0.8636 -0.4064)
			(end -1.1938 -0.4064)
			(stroke
				(width 0.1)
				(type default)
			)
			(layer "B.Fab")
		)
		(fp_line
			(start -0.8636 -0.4572)
			(end -0.8636 -0.4064)
			(stroke
				(width 0.1)
				(type default)
			)
			(layer "B.Fab")
		)
		(fp_line
			(start -1.1938 0.4064)
			(end -0.8636 0.4064)
			(stroke
				(width 0.1)
				(type default)
			)
			(layer "B.Fab")
		)
		(fp_line
			(start -1.1938 -0.4064)
			(end -1.1938 0.4064)
			(stroke
				(width 0.1)
				(type default)
			)
			(layer "B.Fab")
		)
		(pad "1" smd rect
			(at 0.7366 0 90)
			(size 0.7112 0.8128)
			(layers "B.Cu" "B.Mask" "B.Paste")
			(net "P3V3_AUX_CLK_GEN_VDDA25M_CK440")
		)
		(pad "2" smd rect
			(at -0.7366 0 90)
			(size 0.7112 0.8128)
			(layers "B.Cu" "B.Mask" "B.Paste")
			(net "GND")
		)
	)
	(footprint ""
		(layer "B.Cu")
		(at 119.95912 -259.53212 90)
		(property "Reference" "C478"
			(at 0 0 90)
			(layer "B.SilkS")
			(hide yes)
			(effects
				(font
					(size 1.27 1.27)
				)
				(justify mirror)
			)
		)
		(property "Value" ""
			(at 0 0 90)
			(layer "B.Fab")
			(effects
				(font
					(size 1.27 1.27)
				)
				(justify mirror)
			)
		)
		(duplicate_pad_numbers_are_jumpers no)
		(fp_line
			(start 1.524 -0.762)
			(end -1.524 -0.762)
			(stroke
				(width 0.1524)
				(type default)
			)
			(layer "B.SilkS")
		)
		(fp_line
			(start -1.524 -0.762)
			(end -1.524 0.762)
			(stroke
				(width 0.1524)
				(type default)
			)
			(layer "B.SilkS")
		)
		(fp_line
			(start 1.524 0.762)
			(end 1.524 -0.762)
			(stroke
				(width 0.1524)
				(type default)
			)
			(layer "B.SilkS")
		)
		(fp_line
			(start -1.524 0.762)
			(end 1.524 0.762)
			(stroke
				(width 0.1524)
				(type default)
			)
			(layer "B.SilkS")
		)
		(fp_line
			(start 1.1049 -0.724916)
			(end 1.1049 0.724916)
			(stroke
				(width 0.1)
				(type default)
			)
			(layer "B.Fab")
		)
		(fp_line
			(start -1.1049 -0.724916)
			(end 1.1049 -0.724916)
			(stroke
				(width 0.1)
				(type default)
			)
			(layer "B.Fab")
		)
		(fp_line
			(start 1.1049 0.724916)
			(end -1.1049 0.724916)
			(stroke
				(width 0.1)
				(type default)
			)
			(layer "B.Fab")
		)
		(fp_line
			(start -1.1049 0.724916)
			(end -1.1049 -0.724916)
			(stroke
				(width 0.1)
				(type default)
			)
			(layer "B.Fab")
		)
		(pad "1" smd rect
			(at 0.889 0 90)
			(size 1.016 1.27)
			(layers "B.Cu" "B.Mask" "B.Paste")
			(net "PVCCINFAON_CPU1")
		)
		(pad "2" smd rect
			(at -0.889 0 90)
			(size 1.016 1.27)
			(layers "B.Cu" "B.Mask" "B.Paste")
			(net "GND")
		)
	)
)
